(kicad_pcb
	(version 20241229)
	(generator "pcbnew")
	(generator_version "9.0")
	(general
		(thickness 1.6296)
		(legacy_teardrops no)
	)
	(paper "A3")
	(title_block
		(title "Thunderbolt to 10GbE adapter")
		(date "2026-04-21")
		(rev "1.1.0")
		(company "Antmicro Ltd")
		(comment 1 "www.antmicro.com")
		(comment 9 "footprints 164-168 of 703")
	)
	(layers
		(0 "F.Cu" signal)
		(4 "In1.Cu" signal)
		(6 "In2.Cu" signal)
		(8 "In3.Cu" signal)
		(10 "In4.Cu" signal)
		(12 "In5.Cu" signal)
		(14 "In6.Cu" signal)
		(2 "B.Cu" signal)
		(9 "F.Adhes" user "F.Adhesive")
		(11 "B.Adhes" user "B.Adhesive")
		(13 "F.Paste" user)
		(15 "B.Paste" user)
		(5 "F.SilkS" user "F.Silkscreen")
		(7 "B.SilkS" user "B.Silkscreen")
		(1 "F.Mask" user)
		(3 "B.Mask" user)
		(17 "Dwgs.User" user "User.Drawings")
		(19 "Cmts.User" user "User.Comments")
		(21 "Eco1.User" user "User.Eco1")
		(23 "Eco2.User" user "User.Eco2")
		(25 "Edge.Cuts" user)
		(27 "Margin" user)
		(31 "F.CrtYd" user "F.Courtyard")
		(29 "B.CrtYd" user "B.Courtyard")
		(35 "F.Fab" user)
		(33 "B.Fab" user)
	)
	(footprint "antmicro-footprints:C_0402_1005Metric"
		(layer "F.Cu")
		(at 153.8 50.2 90)
		(descr "Capacitor SMD 0402")
		(tags "capacitor SMD 0402")
		(property "Reference" "C314"
			(at -2.1 -0.7 90)
			(layer "F.SilkS")
			(effects
				(font
					(size 0.7 0.7)
					(thickness 0.15)
				)
				(justify left bottom)
			)
		)
		(property "Value" "C_100n_0402"
			(at -1.022927 2.155213 90)
			(layer "F.Fab")
			(effects
				(font
					(size 0.7 0.7)
					(thickness 0.15)
				)
				(justify left bottom)
			)
		)
		(property "Datasheet" "https://www.murata.com/products/productdetail?partno=GRM155R61H104KE14%23"
			(at 0 0 90)
			(layer "F.Fab")
			(hide yes)
			(effects
				(font
					(size 1.27 1.27)
					(thickness 0.15)
				)
			)
		)
		(property "Description" "SMD Multilayer Ceramic Capacitor, 0.1 µF, 50 V, 0402 [1005 Metric], ± 10%, X5R, GRM Series"
			(at 0 0 90)
			(layer "F.Fab")
			(hide yes)
			(effects
				(font
					(size 1.27 1.27)
					(thickness 0.15)
				)
			)
		)
		(property "MPN" "GRM155R61H104KE14D"
			(at 0 0 90)
			(unlocked yes)
			(layer "F.Fab")
			(hide yes)
			(effects
				(font
					(size 1 1)
					(thickness 0.15)
				)
			)
		)
		(property "Manufacturer" "Murata"
			(at 0 0 90)
			(unlocked yes)
			(layer "F.Fab")
			(hide yes)
			(effects
				(font
					(size 1 1)
					(thickness 0.15)
				)
			)
		)
		(property "License" "Apache-2.0"
			(at 0 0 90)
			(unlocked yes)
			(layer "F.Fab")
			(hide yes)
			(effects
				(font
					(size 1 1)
					(thickness 0.15)
				)
			)
		)
		(property "Author" "Antmicro"
			(at 0 0 90)
			(unlocked yes)
			(layer "F.Fab")
			(hide yes)
			(effects
				(font
					(size 1 1)
					(thickness 0.15)
				)
			)
		)
		(property "Val" "100n"
			(at 0 0 90)
			(unlocked yes)
			(layer "F.Fab")
			(hide yes)
			(effects
				(font
					(size 1 1)
					(thickness 0.15)
				)
			)
		)
		(property "Voltage" "50V"
			(at 0 0 90)
			(unlocked yes)
			(layer "F.Fab")
			(hide yes)
			(effects
				(font
					(size 1 1)
					(thickness 0.15)
				)
			)
		)
		(property "Dielectric" "X5R"
			(at 0 0 90)
			(unlocked yes)
			(layer "F.Fab")
			(hide yes)
			(effects
				(font
					(size 1 1)
					(thickness 0.15)
				)
			)
		)
		(sheetname "/Power input/")
		(sheetfile "power_input.kicad_sch")
		(attr smd)
		(fp_rect
			(start -0.925 -0.47)
			(end 0.925 0.47)
			(stroke
				(width 0.05)
				(type default)
			)
			(fill no)
			(layer "F.CrtYd")
		)
		(fp_line
			(start 0.504 -0.25)
			(end 0.504 0.248)
			(stroke
				(width 0.15)
				(type solid)
			)
			(layer "F.Fab")
		)
		(fp_line
			(start -0.494 -0.25)
			(end 0.504 -0.25)
			(stroke
				(width 0.15)
				(type solid)
			)
			(layer "F.Fab")
		)
		(fp_line
			(start 0.504 0.248)
			(end -0.494 0.248)
			(stroke
				(width 0.15)
				(type solid)
			)
			(layer "F.Fab")
		)
		(fp_line
			(start -0.494 0.248)
			(end -0.494 -0.25)
			(stroke
				(width 0.15)
				(type solid)
			)
			(layer "F.Fab")
		)
		(fp_text user "${REFERENCE}"
			(at -0.939 4.599 90)
			(layer "F.Fab")
			(effects
				(font
					(size 0.7 0.7)
					(thickness 0.15)
				)
				(justify left bottom)
			)
		)
		(fp_text user "License: Apache-2.0"
			(at -0.939 5.799 90)
			(layer "F.Fab")
			(effects
				(font
					(size 0.7 0.7)
					(thickness 0.15)
				)
				(justify left bottom)
			)
		)
		(fp_text user "Author: Antmicro"
			(at -0.939 3.399 90)
			(layer "F.Fab")
			(effects
				(font
					(size 0.7 0.7)
					(thickness 0.15)
				)
				(justify left bottom)
			)
		)
		(pad "1" smd roundrect
			(at -0.48 0 90)
			(size 0.59 0.64)
			(layers "F.Cu" "F.Mask" "F.Paste")
			(roundrect_rratio 0.25)
			(net 23 "GND")
			(pintype "passive")
		)
		(pad "2" smd roundrect
			(at 0.48 0 90)
			(size 0.59 0.64)
			(layers "F.Cu" "F.Mask" "F.Paste")
			(roundrect_rratio 0.25)
			(net 412 "Net-(D15-C)")
			(pintype "passive")
		)
	)
	(footprint "antmicro-footprints:C_0402_1005Metric"
		(layer "F.Cu")
		(at 161.355001 99.204999 -90)
		(descr "Capacitor SMD 0402")
		(tags "capacitor SMD 0402")
		(property "Reference" "C163"
			(at 0 -7.695 270)
			(layer "F.SilkS")
			(effects
				(font
					(size 0.7 0.7)
					(thickness 0.15)
				)
			)
		)
		(property "Value" "C_100n_0402"
			(at -1.022927 2.155213 270)
			(layer "F.Fab")
			(effects
				(font
					(size 0.7 0.7)
					(thickness 0.15)
				)
				(justify left bottom)
			)
		)
		(property "Datasheet" "https://www.murata.com/products/productdetail?partno=GRM155R61H104KE14%23"
			(at 0 0 270)
			(layer "F.Fab")
			(hide yes)
			(effects
				(font
					(size 1.27 1.27)
					(thickness 0.15)
				)
			)
		)
		(property "Description" "SMD Multilayer Ceramic Capacitor, 0.1 µF, 50 V, 0402 [1005 Metric], ± 10%, X5R, GRM Series"
			(at 0 0 270)
			(layer "F.Fab")
			(hide yes)
			(effects
				(font
					(size 1.27 1.27)
					(thickness 0.15)
				)
			)
		)
		(property "MPN" "GRM155R61H104KE14D"
			(at 0 0 270)
			(unlocked yes)
			(layer "F.Fab")
			(hide yes)
			(effects
				(font
					(size 1 1)
					(thickness 0.15)
				)
			)
		)
		(property "Val" "100n"
			(at 0 0 270)
			(unlocked yes)
			(layer "F.Fab")
			(hide yes)
			(effects
				(font
					(size 1 1)
					(thickness 0.15)
				)
			)
		)
		(property "Voltage" "50V"
			(at 0 0 270)
			(unlocked yes)
			(layer "F.Fab")
			(hide yes)
			(effects
				(font
					(size 1 1)
					(thickness 0.15)
				)
			)
		)
		(property "Dielectric" "X5R"
			(at 0 0 270)
			(unlocked yes)
			(layer "F.Fab")
			(hide yes)
			(effects
				(font
					(size 1 1)
					(thickness 0.15)
				)
			)
		)
		(property "Manufacturer" "Murata"
			(at 0 0 270)
			(unlocked yes)
			(layer "F.Fab")
			(hide yes)
			(effects
				(font
					(size 1 1)
					(thickness 0.15)
				)
			)
		)
		(property "License" "Apache-2.0"
			(at 0 0 270)
			(unlocked yes)
			(layer "F.Fab")
			(hide yes)
			(effects
				(font
					(size 1 1)
					(thickness 0.15)
				)
			)
		)
		(property "Author" "Antmicro"
			(at 0 0 270)
			(unlocked yes)
			(layer "F.Fab")
			(hide yes)
			(effects
				(font
					(size 1 1)
					(thickness 0.15)
				)
			)
		)
		(sheetname "/X710-AT2 power/")
		(sheetfile "x710-at2-power.kicad_sch")
		(attr smd)
		(fp_rect
			(start -0.925 -0.47)
			(end 0.925 0.47)
			(stroke
				(width 0.05)
				(type default)
			)
			(fill no)
			(layer "F.CrtYd")
		)
		(fp_line
			(start -0.494 0.248)
			(end -0.494 -0.25)
			(stroke
				(width 0.15)
				(type solid)
			)
			(layer "F.Fab")
		)
		(fp_line
			(start 0.504 0.248)
			(end -0.494 0.248)
			(stroke
				(width 0.15)
				(type solid)
			)
			(layer "F.Fab")
		)
		(fp_line
			(start -0.494 -0.25)
			(end 0.504 -0.25)
			(stroke
				(width 0.15)
				(type solid)
			)
			(layer "F.Fab")
		)
		(fp_line
			(start 0.504 -0.25)
			(end 0.504 0.248)
			(stroke
				(width 0.15)
				(type solid)
			)
			(layer "F.Fab")
		)
		(fp_text user "License: Apache-2.0"
			(at -0.939 5.799 270)
			(layer "F.Fab")
			(effects
				(font
					(size 0.7 0.7)
					(thickness 0.15)
				)
				(justify left bottom)
			)
		)
		(fp_text user "${REFERENCE}"
			(at -0.939 4.599 270)
			(layer "F.Fab")
			(effects
				(font
					(size 0.7 0.7)
					(thickness 0.15)
				)
				(justify left bottom)
			)
		)
		(fp_text user "Author: Antmicro"
			(at -0.939 3.399 270)
			(layer "F.Fab")
			(effects
				(font
					(size 0.7 0.7)
					(thickness 0.15)
				)
				(justify left bottom)
			)
		)
		(pad "1" smd roundrect
			(at -0.48 0 270)
			(size 0.59 0.64)
			(layers "F.Cu" "F.Mask" "F.Paste")
			(roundrect_rratio 0.25)
			(net 23 "GND")
			(pintype "passive")
		)
		(pad "2" smd roundrect
			(at 0.48 0 270)
			(size 0.59 0.64)
			(layers "F.Cu" "F.Mask" "F.Paste")
			(roundrect_rratio 0.25)
			(net 136 "+1V0")
			(pintype "passive")
		)
	)
	(footprint "antmicro-footprints:C_0603_1608Metric_EIA"
		(layer "F.Cu")
		(at 144.404999 99.774999 -90)
		(descr "Capacitor SMD 0603, IPC-7351 Density Level A")
		(tags "Capacitor 0603")
		(property "Reference" "C165"
			(at -9.274999 -34.845001 270)
			(layer "F.SilkS")
			(effects
				(font
					(size 0.7 0.7)
					(thickness 0.15)
				)
			)
		)
		(property "Value" "C_22u_16V_0603"
			(at -1.42757 1.770288 270)
			(layer "F.Fab")
			(effects
				(font
					(size 0.7 0.7)
					(thickness 0.15)
				)
				(justify left bottom)
			)
		)
		(property "Datasheet" "https://product.samsungsem.com/mlcc/CL10A226MO7JZN.do"
			(at 0 0 270)
			(layer "F.Fab")
			(hide yes)
			(effects
				(font
					(size 1.27 1.27)
					(thickness 0.15)
				)
			)
		)
		(property "Description" "SMD Multilayer Ceramic Capacitor"
			(at 0 0 270)
			(layer "F.Fab")
			(hide yes)
			(effects
				(font
					(size 1.27 1.27)
					(thickness 0.15)
				)
			)
		)
		(property "MPN" "CL10A226MO7JZNC"
			(at 0 0 270)
			(unlocked yes)
			(layer "F.Fab")
			(hide yes)
			(effects
				(font
					(size 1 1)
					(thickness 0.15)
				)
			)
		)
		(property "Manufacturer" "Samsung Electro-Mechanics"
			(at 0 0 270)
			(unlocked yes)
			(layer "F.Fab")
			(hide yes)
			(effects
				(font
					(size 1 1)
					(thickness 0.15)
				)
			)
		)
		(property "License" "Apache-2.0"
			(at 0 0 270)
			(unlocked yes)
			(layer "F.Fab")
			(hide yes)
			(effects
				(font
					(size 1 1)
					(thickness 0.15)
				)
			)
		)
		(property "Author" "Antmicro"
			(at 0 0 270)
			(unlocked yes)
			(layer "F.Fab")
			(hide yes)
			(effects
				(font
					(size 1 1)
					(thickness 0.15)
				)
			)
		)
		(property "Val" "22u"
			(at 0 0 270)
			(unlocked yes)
			(layer "F.Fab")
			(hide yes)
			(effects
				(font
					(size 1 1)
					(thickness 0.15)
				)
			)
		)
		(property "Voltage" "16V"
			(at 0 0 270)
			(unlocked yes)
			(layer "F.Fab")
			(hide yes)
			(effects
				(font
					(size 1 1)
					(thickness 0.15)
				)
			)
		)
		(property "Dielectric" ""
			(at 0 0 270)
			(unlocked yes)
			(layer "F.Fab")
			(hide yes)
			(effects
				(font
					(size 1 1)
					(thickness 0.15)
				)
			)
		)
		(sheetname "/X710-AT2 power/")
		(sheetfile "x710-at2-power.kicad_sch")
		(attr smd)
		(fp_line
			(start -0.15 0.55)
			(end 0.15 0.55)
			(stroke
				(width 0.15)
				(type solid)
			)
			(layer "F.SilkS")
		)
		(fp_line
			(start -0.15 -0.55)
			(end 0.15 -0.55)
			(stroke
				(width 0.15)
				(type solid)
			)
			(layer "F.SilkS")
		)
		(fp_rect
			(start -1.25 -0.65)
			(end 1.25 0.65)
			(stroke
				(width 0.05)
				(type solid)
			)
			(fill no)
			(layer "F.CrtYd")
		)
		(fp_rect
			(start -0.8 -0.45)
			(end 0.8 0.45)
			(stroke
				(width 0.15)
				(type solid)
			)
			(fill no)
			(layer "F.Fab")
		)
		(fp_text user "License: Apache-2.0"
			(at -1.682 5.895 270)
			(layer "F.Fab")
			(effects
				(font
					(size 0.7 0.7)
					(thickness 0.15)
				)
				(justify left bottom)
			)
		)
		(fp_text user "Author: Antmicro"
			(at -1.682 4.894 270)
			(layer "F.Fab")
			(effects
				(font
					(size 0.7 0.7)
					(thickness 0.15)
				)
				(justify left bottom)
			)
		)
		(fp_text user "${REFERENCE}"
			(at -1.682 3.895 270)
			(layer "F.Fab")
			(effects
				(font
					(size 0.7 0.7)
					(thickness 0.15)
				)
				(justify left bottom)
			)
		)
		(pad "1" smd roundrect
			(at -0.7 0 270)
			(size 0.8 1.1)
			(layers "F.Cu" "F.Mask" "F.Paste")
			(roundrect_rratio 0.2)
			(net 23 "GND")
			(pintype "passive")
		)
		(pad "2" smd roundrect
			(at 0.7 0 270)
			(size 0.8 1.1)
			(layers "F.Cu" "F.Mask" "F.Paste")
			(roundrect_rratio 0.2)
			(net 6 "DVDD")
			(pintype "passive")
		)
	)
	(footprint "antmicro-footprints:C_0402_1005Metric"
		(layer "F.Cu")
		(at 171.6 74 90)
		(descr "Capacitor SMD 0402")
		(tags "capacitor SMD 0402")
		(property "Reference" "C284"
			(at -1.2 3.6 90)
			(layer "F.SilkS")
			(effects
				(font
					(size 0.7 0.7)
					(thickness 0.15)
				)
				(justify left bottom)
			)
		)
		(property "Value" "C_10p_25V_0402"
			(at -1.022927 2.155213 90)
			(layer "F.Fab")
			(effects
				(font
					(size 0.7 0.7)
					(thickness 0.15)
				)
				(justify left bottom)
			)
		)
		(property "Datasheet" "https://spicat.kyocera-avx.com/product/mlcc/chartview/04023A100FAT2A/"
			(at 0 0 90)
			(layer "F.Fab")
			(hide yes)
			(effects
				(font
					(size 1.27 1.27)
					(thickness 0.15)
				)
			)
		)
		(property "Description" "Multilayer Ceramic Capacitors MLCC - SMD/SMT 25V 10pF C0G 0402 1%"
			(at 0 0 90)
			(layer "F.Fab")
			(hide yes)
			(effects
				(font
					(size 1.27 1.27)
					(thickness 0.15)
				)
			)
		)
		(property "MPN" "04023A100FAT2A"
			(at 0 0 90)
			(unlocked yes)
			(layer "F.Fab")
			(hide yes)
			(effects
				(font
					(size 1 1)
					(thickness 0.15)
				)
			)
		)
		(property "Manufacturer" "KYOCERA AVX"
			(at 0 0 90)
			(unlocked yes)
			(layer "F.Fab")
			(hide yes)
			(effects
				(font
					(size 1 1)
					(thickness 0.15)
				)
			)
		)
		(property "License" "Apache-2.0"
			(at 0 0 90)
			(unlocked yes)
			(layer "F.Fab")
			(hide yes)
			(effects
				(font
					(size 1 1)
					(thickness 0.15)
				)
			)
		)
		(property "Author" "Antmicro"
			(at 0 0 90)
			(unlocked yes)
			(layer "F.Fab")
			(hide yes)
			(effects
				(font
					(size 1 1)
					(thickness 0.15)
				)
			)
		)
		(property "Val" "10p"
			(at 0 0 90)
			(unlocked yes)
			(layer "F.Fab")
			(hide yes)
			(effects
				(font
					(size 1 1)
					(thickness 0.15)
				)
			)
		)
		(property "Voltage" "25V"
			(at 0 0 90)
			(unlocked yes)
			(layer "F.Fab")
			(hide yes)
			(effects
				(font
					(size 1 1)
					(thickness 0.15)
				)
			)
		)
		(property "Dielectric" "C0G"
			(at 0 0 90)
			(unlocked yes)
			(layer "F.Fab")
			(hide yes)
			(effects
				(font
					(size 1 1)
					(thickness 0.15)
				)
			)
		)
		(sheetname "/X710-AT2 10GbE/")
		(sheetfile "x710-at2-10gbe.kicad_sch")
		(attr smd)
		(fp_rect
			(start -0.925 -0.47)
			(end 0.925 0.47)
			(stroke
				(width 0.05)
				(type default)
			)
			(fill no)
			(layer "F.CrtYd")
		)
		(fp_line
			(start 0.504 -0.25)
			(end 0.504 0.248)
			(stroke
				(width 0.15)
				(type solid)
			)
			(layer "F.Fab")
		)
		(fp_line
			(start -0.494 -0.25)
			(end 0.504 -0.25)
			(stroke
				(width 0.15)
				(type solid)
			)
			(layer "F.Fab")
		)
		(fp_line
			(start 0.504 0.248)
			(end -0.494 0.248)
			(stroke
				(width 0.15)
				(type solid)
			)
			(layer "F.Fab")
		)
		(fp_line
			(start -0.494 0.248)
			(end -0.494 -0.25)
			(stroke
				(width 0.15)
				(type solid)
			)
			(layer "F.Fab")
		)
		(fp_text user "License: Apache-2.0"
			(at -0.939 5.799 90)
			(layer "F.Fab")
			(effects
				(font
					(size 0.7 0.7)
					(thickness 0.15)
				)
				(justify left bottom)
			)
		)
		(fp_text user "Author: Antmicro"
			(at -0.939 3.399 90)
			(layer "F.Fab")
			(effects
				(font
					(size 0.7 0.7)
					(thickness 0.15)
				)
				(justify left bottom)
			)
		)
		(fp_text user "${REFERENCE}"
			(at -0.939 4.599 90)
			(layer "F.Fab")
			(effects
				(font
					(size 0.7 0.7)
					(thickness 0.15)
				)
				(justify left bottom)
			)
		)
		(pad "1" smd roundrect
			(at -0.48 0 90)
			(size 0.59 0.64)
			(layers "F.Cu" "F.Mask" "F.Paste")
			(roundrect_rratio 0.25)
			(net 23 "GND")
			(pintype "passive")
		)
		(pad "2" smd roundrect
			(at 0.48 0 90)
			(size 0.59 0.64)
			(layers "F.Cu" "F.Mask" "F.Paste")
			(roundrect_rratio 0.25)
			(net 122 "/X710-AT2 10GbE/MDIO0_I2C0.MDIO")
			(pintype "passive")
		)
	)
	(footprint "antmicro-footprints:C_0402_1005Metric"
		(layer "F.Cu")
		(at 139.5 111.85)
		(descr "Capacitor SMD 0402")
		(tags "capacitor SMD 0402")
		(property "Reference" "C115"
			(at 16 16.799998 0)
			(layer "F.SilkS")
			(effects
				(font
					(size 0.7 0.7)
					(thickness 0.15)
				)
			)
		)
		(property "Value" "C_100n_0402"
			(at -1.022927 2.155213 0)
			(layer "F.Fab")
			(effects
				(font
					(size 0.7 0.7)
					(thickness 0.15)
				)
				(justify left bottom)
			)
		)
		(property "Datasheet" "https://www.murata.com/products/productdetail?partno=GRM155R61H104KE14%23"
			(at 0 0 0)
			(layer "F.Fab")
			(hide yes)
			(effects
				(font
					(size 1.27 1.27)
					(thickness 0.15)
				)
			)
		)
		(property "Description" "SMD Multilayer Ceramic Capacitor, 0.1 µF, 50 V, 0402 [1005 Metric], ± 10%, X5R, GRM Series"
			(at 0 0 0)
			(layer "F.Fab")
			(hide yes)
			(effects
				(font
					(size 1.27 1.27)
					(thickness 0.15)
				)
			)
		)
		(property "MPN" "GRM155R61H104KE14D"
			(at 0 0 0)
			(unlocked yes)
			(layer "F.Fab")
			(hide yes)
			(effects
				(font
					(size 1 1)
					(thickness 0.15)
				)
			)
		)
		(property "Manufacturer" "Murata"
			(at 0 0 0)
			(unlocked yes)
			(layer "F.Fab")
			(hide yes)
			(effects
				(font
					(size 1 1)
					(thickness 0.15)
				)
			)
		)
		(property "License" "Apache-2.0"
			(at 0 0 0)
			(unlocked yes)
			(layer "F.Fab")
			(hide yes)
			(effects
				(font
					(size 1 1)
					(thickness 0.15)
				)
			)
		)
		(property "Author" "Antmicro"
			(at 0 0 0)
			(unlocked yes)
			(layer "F.Fab")
			(hide yes)
			(effects
				(font
					(size 1 1)
					(thickness 0.15)
				)
			)
		)
		(property "Val" "100n"
			(at 0 0 0)
			(unlocked yes)
			(layer "F.Fab")
			(hide yes)
			(effects
				(font
					(size 1 1)
					(thickness 0.15)
				)
			)
		)
		(property "Voltage" "50V"
			(at 0 0 0)
			(unlocked yes)
			(layer "F.Fab")
			(hide yes)
			(effects
				(font
					(size 1 1)
					(thickness 0.15)
				)
			)
		)
		(property "Dielectric" "X5R"
			(at 0 0 0)
			(unlocked yes)
			(layer "F.Fab")
			(hide yes)
			(effects
				(font
					(size 1 1)
					(thickness 0.15)
				)
			)
		)
		(sheetname "/X710 DCDC converters/")
		(sheetfile "DCDC_converters_X710.kicad_sch")
		(attr smd)
		(fp_rect
			(start -0.925 -0.47)
			(end 0.925 0.47)
			(stroke
				(width 0.05)
				(type default)
			)
			(fill no)
			(layer "F.CrtYd")
		)
		(fp_line
			(start -0.494 -0.25)
			(end 0.504 -0.25)
			(stroke
				(width 0.15)
				(type solid)
			)
			(layer "F.Fab")
		)
		(fp_line
			(start -0.494 0.248)
			(end -0.494 -0.25)
			(stroke
				(width 0.15)
				(type solid)
			)
			(layer "F.Fab")
		)
		(fp_line
			(start 0.504 -0.25)
			(end 0.504 0.248)
			(stroke
				(width 0.15)
				(type solid)
			)
			(layer "F.Fab")
		)
		(fp_line
			(start 0.504 0.248)
			(end -0.494 0.248)
			(stroke
				(width 0.15)
				(type solid)
			)
			(layer "F.Fab")
		)
		(fp_text user "Author: Antmicro"
			(at -0.939 3.399 0)
			(layer "F.Fab")
			(effects
				(font
					(size 0.7 0.7)
					(thickness 0.15)
				)
				(justify left bottom)
			)
		)
		(fp_text user "License: Apache-2.0"
			(at -0.939 5.799 0)
			(layer "F.Fab")
			(effects
				(font
					(size 0.7 0.7)
					(thickness 0.15)
				)
				(justify left bottom)
			)
		)
		(fp_text user "${REFERENCE}"
			(at -0.939 4.599 0)
			(layer "F.Fab")
			(effects
				(font
					(size 0.7 0.7)
					(thickness 0.15)
				)
				(justify left bottom)
			)
		)
		(pad "1" smd roundrect
			(at -0.48 0)
			(size 0.59 0.64)
			(layers "F.Cu" "F.Mask" "F.Paste")
			(roundrect_rratio 0.25)
			(net 23 "GND")
			(pintype "passive")
		)
		(pad "2" smd roundrect
			(at 0.48 0)
			(size 0.59 0.64)
			(layers "F.Cu" "F.Mask" "F.Paste")
			(roundrect_rratio 0.25)
			(net 40 "+5V")
			(pintype "passive")
		)
	)
)
